(kicad_pcb
	(version 20260206)
	(generator "pcbnew")
	(generator_version "10.0")
	(general
		(thickness 1.6)
		(legacy_teardrops no)
	)
	(paper "A4")
	(title_block
		(title "panther-plus-userver — 13130-1b_20150205.brd")
		(comment 1 "Honey Badger (Wiwynn) / footprints 1211-1213 of 1509")
	)
	(layers
		(0 "F.Cu" signal "TOP")
		(4 "In1.Cu" signal "L2")
		(6 "In2.Cu" signal "L3")
		(8 "In3.Cu" signal "L4")
		(10 "In4.Cu" signal "L5")
		(12 "In5.Cu" signal "L6")
		(14 "In6.Cu" signal "L7")
		(16 "In7.Cu" signal "L8")
		(18 "In8.Cu" signal "L9")
		(20 "In9.Cu" signal "L10")
		(22 "In10.Cu" signal "L11")
		(2 "B.Cu" signal "BOTTOM")
		(9 "F.Adhes" user "F.Adhesive")
		(11 "B.Adhes" user "B.Adhesive")
		(13 "F.Paste" user "Package Geometry/Pastemask Top")
		(15 "B.Paste" user "Package Geometry/Pastemask Bottom")
		(5 "F.SilkS" user "Ref Des/Silkscreen Top")
		(7 "B.SilkS" user "Ref Des/Silkscreen Bottom")
		(1 "F.Mask" user "Board Geometry/Soldermask Top")
		(3 "B.Mask" user "Board Geometry/Soldermask Bottom")
		(17 "Dwgs.User" user "User.Drawings")
		(19 "Cmts.User" user "User.Comments")
		(21 "Eco1.User" user "User.Eco1")
		(23 "Eco2.User" user "User.Eco2")
		(25 "Edge.Cuts" user "Board Geometry/Outline")
		(27 "Margin" user)
		(31 "F.CrtYd" user "Package Geometry/Place Bound Top")
		(29 "B.CrtYd" user "Package Geometry/Place Bound Bottom")
		(35 "F.Fab" user "Ref Des/Assembly Top")
		(33 "B.Fab" user "Ref Des/Assembly Bottom")
	)
	(footprint ""
		(layer "B.Cu")
		(at 103.3018 -44.720002 90)
		(property "Reference" "C153"
			(at 0 0 90)
			(layer "B.SilkS")
			(hide yes)
			(effects
				(font
					(size 1.27 1.27)
				)
				(justify mirror)
			)
		)
		(property "Value" "SC1U10V2KX-1GP"
			(at -1.1811 -2.7051 90)
			(unlocked yes)
			(layer "B.Fab")
			(hide yes)
			(effects
				(font
					(size 1.016 1.016)
					(thickness 0.1524)
				)
				(justify mirror)
			)
		)
		(property "Device Type" "C402H22"
			(at -1.1811 -4.2291 90)
			(unlocked yes)
			(layer "B.Fab")
			(hide yes)
			(effects
				(font
					(size 1.016 1.016)
					(thickness 0.1524)
				)
				(justify mirror)
			)
		)
		(duplicate_pad_numbers_are_jumpers no)
		(fp_rect
			(start 0.381 0.7366)
			(end -0.381 -0.7366)
			(stroke
				(width 0)
				(type default)
			)
			(fill no)
			(layer "B.CrtYd")
		)
		(fp_rect
			(start 0.381 0.7366)
			(end -0.381 -0.7366)
			(stroke
				(width 0)
				(type default)
			)
			(fill no)
			(layer "B.Fab")
		)
		(pad "1" smd custom
			(at 0 -0.4572 270)
			(size 0.1143 0.1143)
			(layers "B.Cu" "B.Mask" "B.Paste")
			(net "P1V0")
			(options
				(clearance outline)
				(anchor circle)
			)
			(primitives
				(gr_poly
					(pts
						(arc
							(start -0.254 0.1778)
							(mid -0.239121 0.213721)
							(end -0.2032 0.2286)
						)
						(arc
							(start 0.2032 0.2286)
							(mid 0.239121 0.213721)
							(end 0.254 0.1778)
						)
						(arc
							(start 0.254 -0.1778)
							(mid 0.239121 -0.213721)
							(end 0.2032 -0.2286)
						)
						(arc
							(start -0.2032 -0.2286)
							(mid -0.239121 -0.213721)
							(end -0.254 -0.1778)
						)
					)
					(width 0)
					(fill yes)
				)
			)
		)
		(pad "2" smd custom
			(at 0 0.4572 270)
			(size 0.1143 0.1143)
			(layers "B.Cu" "B.Mask" "B.Paste")
			(net "GND")
			(options
				(clearance outline)
				(anchor circle)
			)
			(primitives
				(gr_poly
					(pts
						(arc
							(start -0.254 0.1778)
							(mid -0.239121 0.213721)
							(end -0.2032 0.2286)
						)
						(arc
							(start 0.2032 0.2286)
							(mid 0.239121 0.213721)
							(end 0.254 0.1778)
						)
						(arc
							(start 0.254 -0.1778)
							(mid 0.239121 -0.213721)
							(end 0.2032 -0.2286)
						)
						(arc
							(start -0.2032 -0.2286)
							(mid -0.239121 -0.213721)
							(end -0.254 -0.1778)
						)
					)
					(width 0)
					(fill yes)
				)
			)
		)
	)
	(footprint ""
		(layer "B.Cu")
		(at 103.251 -34.814002 90)
		(property "Reference" "C210"
			(at 0 0 90)
			(layer "B.SilkS")
			(hide yes)
			(effects
				(font
					(size 1.27 1.27)
				)
				(justify mirror)
			)
		)
		(property "Value" "SC2D2U10V2KX-GP"
			(at -1.1811 -2.7051 90)
			(unlocked yes)
			(layer "B.Fab")
			(hide yes)
			(effects
				(font
					(size 1.016 1.016)
					(thickness 0.1524)
				)
				(justify mirror)
			)
		)
		(property "Device Type" "C402H22"
			(at -1.1811 -4.2291 90)
			(unlocked yes)
			(layer "B.Fab")
			(hide yes)
			(effects
				(font
					(size 1.016 1.016)
					(thickness 0.1524)
				)
				(justify mirror)
			)
		)
		(duplicate_pad_numbers_are_jumpers no)
		(fp_rect
			(start 0.381 0.7366)
			(end -0.381 -0.7366)
			(stroke
				(width 0)
				(type default)
			)
			(fill no)
			(layer "B.CrtYd")
		)
		(fp_rect
			(start 0.381 0.7366)
			(end -0.381 -0.7366)
			(stroke
				(width 0)
				(type default)
			)
			(fill no)
			(layer "B.Fab")
		)
		(pad "1" smd custom
			(at 0 -0.4572 270)
			(size 0.1143 0.1143)
			(layers "B.Cu" "B.Mask" "B.Paste")
			(net "P1V0")
			(options
				(clearance outline)
				(anchor circle)
			)
			(primitives
				(gr_poly
					(pts
						(arc
							(start -0.254 0.1778)
							(mid -0.239121 0.213721)
							(end -0.2032 0.2286)
						)
						(arc
							(start 0.2032 0.2286)
							(mid 0.239121 0.213721)
							(end 0.254 0.1778)
						)
						(arc
							(start 0.254 -0.1778)
							(mid 0.239121 -0.213721)
							(end 0.2032 -0.2286)
						)
						(arc
							(start -0.2032 -0.2286)
							(mid -0.239121 -0.213721)
							(end -0.254 -0.1778)
						)
					)
					(width 0)
					(fill yes)
				)
			)
		)
		(pad "2" smd custom
			(at 0 0.4572 270)
			(size 0.1143 0.1143)
			(layers "B.Cu" "B.Mask" "B.Paste")
			(net "GND")
			(options
				(clearance outline)
				(anchor circle)
			)
			(primitives
				(gr_poly
					(pts
						(arc
							(start -0.254 0.1778)
							(mid -0.239121 0.213721)
							(end -0.2032 0.2286)
						)
						(arc
							(start 0.2032 0.2286)
							(mid 0.239121 0.213721)
							(end 0.254 0.1778)
						)
						(arc
							(start 0.254 -0.1778)
							(mid 0.239121 -0.213721)
							(end 0.2032 -0.2286)
						)
						(arc
							(start -0.2032 -0.2286)
							(mid -0.239121 -0.213721)
							(end -0.254 -0.1778)
						)
					)
					(width 0)
					(fill yes)
				)
			)
		)
	)
	(footprint ""
		(layer "B.Cu")
		(at 38.735 -41.148 -90)
		(property "Reference" "R14"
			(at 0 0 90)
			(layer "B.SilkS")
			(hide yes)
			(effects
				(font
					(size 1.27 1.27)
				)
				(justify mirror)
			)
		)
		(property "Value" "1KR2F-3-GP"
			(at -0.064008 -3.993896 270)
			(unlocked yes)
			(layer "B.Fab")
			(hide yes)
			(effects
				(font
					(size 1.016 1.016)
					(thickness 0.1524)
				)
				(justify mirror)
			)
		)
		(property "Device Type" "R402H16"
			(at -0.064008 -5.517896 270)
			(unlocked yes)
			(layer "B.Fab")
			(hide yes)
			(effects
				(font
					(size 1.016 1.016)
					(thickness 0.1524)
				)
				(justify mirror)
			)
		)
		(duplicate_pad_numbers_are_jumpers no)
		(fp_rect
			(start 0.381 0.8382)
			(end -0.381 -0.8382)
			(stroke
				(width 0)
				(type default)
			)
			(fill no)
			(layer "B.CrtYd")
		)
		(fp_rect
			(start 0.381 0.8382)
			(end -0.381 -0.8382)
			(stroke
				(width 0)
				(type default)
			)
			(fill no)
			(layer "B.Fab")
		)
		(pad "1" smd custom
			(at 0 -0.4318 90)
			(size 0.127 0.127)
			(layers "B.Cu" "B.Mask" "B.Paste")
			(net "P3V3")
			(options
				(clearance outline)
				(anchor circle)
			)
			(primitives
				(gr_poly
					(pts
						(arc
							(start -0.2032 0.2794)
							(mid -0.239121 0.264521)
							(end -0.254 0.2286)
						)
						(arc
							(start -0.254 -0.2286)
							(mid -0.239121 -0.264521)
							(end -0.2032 -0.2794)
						)
						(arc
							(start 0.2032 -0.2794)
							(mid 0.239121 -0.264521)
							(end 0.254 -0.2286)
						)
						(arc
							(start 0.254 0.2286)
							(mid 0.239121 0.264521)
							(end 0.2032 0.2794)
						)
					)
					(width 0)
					(fill yes)
				)
			)
		)
		(pad "2" smd custom
			(at 0 0.4318 90)
			(size 0.127 0.127)
			(layers "B.Cu" "B.Mask" "B.Paste")
			(net "CORE_PWROK")
			(options
				(clearance outline)
				(anchor circle)
			)
			(primitives
				(gr_poly
					(pts
						(arc
							(start -0.2032 0.2794)
							(mid -0.239121 0.264521)
							(end -0.254 0.2286)
						)
						(arc
							(start -0.254 -0.2286)
							(mid -0.239121 -0.264521)
							(end -0.2032 -0.2794)
						)
						(arc
							(start 0.2032 -0.2794)
							(mid 0.239121 -0.264521)
							(end 0.254 -0.2286)
						)
						(arc
							(start 0.254 0.2286)
							(mid 0.239121 0.264521)
							(end 0.2032 0.2794)
						)
					)
					(width 0)
					(fill yes)
				)
			)
		)
	)
)
